# S9S_MB_2U (Grand Teton) — schematic netlist excerpt (pin names and nets, part order shuffled) for the footprints in the layout excerpt that follows; sources: Cadence DE-HDL packaged netlist, KiCad conversion of 03242023_DA0F0TMBIJ0_F0T_Motherboard_J_brd_V01_OCP.brd

J106  CONN112_10137002101LF  CONN112_10137002-101LF IO  pkg HSD_F112D8_P2W1-2_RDH  page 137
  A1  = PRSNT_CABLE_SWB_B1_N
  A2  = GND
  A3  = FM_SWB_PWRGD
  A4  = GND
  A5  = NC_J106_A5
  A6  = GND
  A7  = PRSNT_CABLE_GPU_A1_N
  A8  = GND
  B1  = GND
  B2  = P5E_CPU0_PE3_RX_DP<14>
  B3  = GND
  B4  = P5E_CPU0_PE3_RX_DP<12>
  B5  = GND
  B6  = P5E_CPU0_PE3_RX_DN<10>
  B7  = GND
  B8  = P5E_CPU0_PE3_RX_DN<8>
  C1  = P5E_CPU0_PE3_RX_DP<15>
  C2  = P5E_CPU0_PE3_RX_DN<14>
  C3  = P5E_CPU0_PE3_RX_DP<13>
  C4  = P5E_CPU0_PE3_RX_DN<12>
  C5  = P5E_CPU0_PE3_RX_DN<11>
  C6  = P5E_CPU0_PE3_RX_DP<10>
  C7  = P5E_CPU0_PE3_RX_DN<9>
  C8  = P5E_CPU0_PE3_RX_DP<8>
  D1  = P5E_CPU0_PE3_RX_DN<15>
  D2  = GND
  D3  = P5E_CPU0_PE3_RX_DN<13>
  D4  = GND
  D5  = P5E_CPU0_PE3_RX_DP<11>
  D6  = GND
  D7  = P5E_CPU0_PE3_RX_DP<9>
  D8  = GND
  E1  = GND
  E2  = P5E_CPU0_PE2_RX_DP<14>
  E3  = GND
  E4  = P5E_CPU0_PE2_RX_DP<12>
  E5  = GND
  E6  = P5E_CPU0_PE2_RX_DP<10>
  E7  = GND
  E8  = P5E_CPU0_PE2_RX_DP<8>
  F1  = P5E_CPU0_PE2_RX_DP<15>
  F2  = P5E_CPU0_PE2_RX_DN<14>
  F3  = P5E_CPU0_PE2_RX_DP<13>
  F4  = P5E_CPU0_PE2_RX_DN<12>
  F5  = P5E_CPU0_PE2_RX_DP<11>
  F6  = P5E_CPU0_PE2_RX_DN<10>
  F7  = P5E_CPU0_PE2_RX_DP<9>
  F8  = P5E_CPU0_PE2_RX_DN<8>
  G1  = P5E_CPU0_PE2_RX_DN<15>
  G2  = GND
  G3  = P5E_CPU0_PE2_RX_DN<13>
  G4  = GND
  G5  = P5E_CPU0_PE2_RX_DN<11>
  G6  = GND
  G7  = P5E_CPU0_PE2_RX_DN<9>
  G8  = GND
  H1  = GND
  H2  = P5E_CPU0_PE3_TX_C_DN<14>
  H3  = GND
  H4  = P5E_CPU0_PE3_TX_C_DN<12>
  H5  = GND
  H6  = P5E_CPU0_PE3_TX_C_DN<10>
  H7  = GND
  H8  = P5E_CPU0_PE3_TX_C_DN<8>
  I1  = P5E_CPU0_PE3_TX_C_DN<15>
  I2  = P5E_CPU0_PE3_TX_C_DP<14>
  I3  = P5E_CPU0_PE3_TX_C_DN<13>
  I4  = P5E_CPU0_PE3_TX_C_DP<12>
  I5  = P5E_CPU0_PE3_TX_C_DN<11>
  I6  = P5E_CPU0_PE3_TX_C_DP<10>
  I7  = P5E_CPU0_PE3_TX_C_DN<9>
  I8  = P5E_CPU0_PE3_TX_C_DP<8>
  J1  = P5E_CPU0_PE3_TX_C_DP<15>
  J2  = GND
  J3  = P5E_CPU0_PE3_TX_C_DP<13>
  J4  = GND
  J5  = P5E_CPU0_PE3_TX_C_DP<11>
  J6  = GND
  J7  = P5E_CPU0_PE3_TX_C_DP<9>
  J8  = GND
  K1  = GND
  K2  = P5E_CPU0_PE2_TX_C_DP<14>
  K3  = GND
  K4  = P5E_CPU0_PE2_TX_C_DP<12>
  K5  = GND
  K6  = P5E_CPU0_PE2_TX_C_DP<10>
  K7  = GND
  K8  = P5E_CPU0_PE2_TX_C_DP<8>
  L1  = P5E_CPU0_PE2_TX_C_DN<15>
  L2  = P5E_CPU0_PE2_TX_C_DN<14>
  L3  = P5E_CPU0_PE2_TX_C_DP<13>
  L4  = P5E_CPU0_PE2_TX_C_DN<12>
  L5  = P5E_CPU0_PE2_TX_C_DP<11>
  L6  = P5E_CPU0_PE2_TX_C_DN<10>
  L7  = P5E_CPU0_PE2_TX_C_DP<9>
  L8  = P5E_CPU0_PE2_TX_C_DN<8>
  M1  = P5E_CPU0_PE2_TX_C_DP<15>
  M2  = GND
  M3  = P5E_CPU0_PE2_TX_C_DN<13>
  M4  = GND
  M5  = P5E_CPU0_PE2_TX_C_DN<11>
  M6  = GND
  M7  = P5E_CPU0_PE2_TX_C_DN<9>
  M8  = GND
  N1  = GND
  N2  = I3C_BMC_SWB_BUF_SDA
  N3  = GND
  N4  = I3C_BMC_SWB_BUF_SCL
  N5  = GND
  N6  = UART_BMC_BIC_RX
  N7  = GND
  N8  = UART_BMC_BIC_TX

(kicad_pcb
	(version 20260206)
	(generator "pcbnew")
	(generator_version "10.0")
	(general
		(thickness 1.6)
		(legacy_teardrops no)
	)
	(paper "A4")
	(title_block
		(title "03242023_DA0F0TMBIJ0_F0T_Motherboard_J_brd_V01_OCP.brd")
		(comment 1 "Grand Teton / footprint 3156 of 6105 (J106), pads 1-31 of 48")
	)
	(layers
		(0 "F.Cu" signal "TOP")
		(4 "In1.Cu" signal "GND")
		(6 "In2.Cu" signal "IN1")
		(8 "In3.Cu" signal "GND1")
		(10 "In4.Cu" signal "IN2")
		(12 "In5.Cu" signal "GND2")
		(14 "In6.Cu" signal "IN3")
		(16 "In7.Cu" signal "GND3")
		(18 "In8.Cu" signal "VCC")
		(20 "In9.Cu" signal "VCC1")
		(22 "In10.Cu" signal "GND4")
		(24 "In11.Cu" signal "IN4")
		(26 "In12.Cu" signal "GND5")
		(28 "In13.Cu" signal "IN5")
		(30 "In14.Cu" signal "GND6")
		(32 "In15.Cu" signal "IN6")
		(34 "In16.Cu" signal "GND7")
		(2 "B.Cu" signal "BOTTOM")
		(9 "F.Adhes" user "F.Adhesive")
		(11 "B.Adhes" user "B.Adhesive")
		(13 "F.Paste" user "Package Geometry/Pastemask Top")
		(15 "B.Paste" user "Package Geometry/Pastemask Bottom")
		(5 "F.SilkS" user "Ref Des/Silkscreen Top")
		(7 "B.SilkS" user "Ref Des/Silkscreen Bottom")
		(1 "F.Mask" user "Board Geometry/Soldermask Top")
		(3 "B.Mask" user "Board Geometry/Soldermask Bottom")
		(17 "Dwgs.User" user "User.Drawings")
		(19 "Cmts.User" user "User.Comments")
		(21 "Eco1.User" user "User.Eco1")
		(23 "Eco2.User" user "User.Eco2")
		(25 "Edge.Cuts" user "Board Geometry/Outline")
		(27 "Margin" user)
		(31 "F.CrtYd" user "Package Geometry/Place Bound Top")
		(29 "B.CrtYd" user "Package Geometry/Place Bound Bottom")
		(35 "F.Fab" user "Ref Des/Assembly Top")
		(33 "B.Fab" user "Ref Des/Assembly Bottom")
	)
	(footprint ""
		(layer "F.Cu")
		(at 381.750062 -440.489848)
		(property "Reference" "J106"
			(at -7.488682 21.48459 0)
			(unlocked yes)
			(layer "F.SilkS")
			(effects
				(font
					(size 0.7874 0.5842)
					(thickness 0.1524)
				)
				(justify left)
			)
		)
		(property "Value" ""
			(at 0 0 0)
			(layer "F.Fab")
			(effects
				(font
					(size 1.27 1.27)
				)
			)
		)
		(duplicate_pad_numbers_are_jumpers no)
		(pad "A1" thru_hole rect
			(at 0 0 180)
			(size 0.766318 0.766318)
			(drill 0.359918)
			(layers "*.Cu" "*.Mask")
			(remove_unused_layers no)
			(net "PRSNT_CABLE_SWB_B1_N")
			(clearance 0.0508)
			(thermal_gap 0.0508)
			(padstack
				(mode front_inner_back)
				(layer "Inner"
					(shape circle)
					(size 0.766318 0.766318)
					(clearance 0.0508)
				)
				(layer "B.Cu"
					(shape rect)
					(size 0.766318 0.766318)
					(clearance 0.0508)
				)
			)
		)
		(pad "A2" thru_hole circle
			(at 1.999996 0.199898 180)
			(size 0.906272 0.906272)
			(drill 0.499872)
			(layers "*.Cu" "*.Mask")
			(remove_unused_layers no)
			(net "GND")
			(clearance 0.0508)
			(thermal_gap 0.0508)
		)
		(pad "A3" thru_hole circle
			(at 3.999992 0 180)
			(size 0.766318 0.766318)
			(drill 0.359918)
			(layers "*.Cu" "*.Mask")
			(remove_unused_layers no)
			(net "FM_SWB_PWRGD")
			(clearance 0.0508)
			(thermal_gap 0.0508)
		)
		(pad "A4" thru_hole circle
			(at 5.999988 0.199898 180)
			(size 0.906272 0.906272)
			(drill 0.499872)
			(layers "*.Cu" "*.Mask")
			(remove_unused_layers no)
			(net "GND")
			(clearance 0.0508)
			(thermal_gap 0.0508)
		)
		(pad "A5" thru_hole circle
			(at 7.999984 0 180)
			(size 0.766318 0.766318)
			(drill 0.359918)
			(layers "*.Cu" "*.Mask")
			(remove_unused_layers no)
			(net "NC_J106_A5")
			(clearance 0.0508)
			(thermal_gap 0.0508)
		)
		(pad "A6" thru_hole circle
			(at 9.99998 0.199898 180)
			(size 0.906272 0.906272)
			(drill 0.499872)
			(layers "*.Cu" "*.Mask")
			(remove_unused_layers no)
			(net "GND")
			(clearance 0.0508)
			(thermal_gap 0.0508)
		)
		(pad "A7" thru_hole circle
			(at 11.999976 0 180)
			(size 0.766318 0.766318)
			(drill 0.359918)
			(layers "*.Cu" "*.Mask")
			(remove_unused_layers no)
			(net "PRSNT_CABLE_GPU_A1_N")
			(clearance 0.0508)
			(thermal_gap 0.0508)
		)
		(pad "A8" thru_hole circle
			(at 13.999972 0.199898 180)
			(size 0.906272 0.906272)
			(drill 0.499872)
			(layers "*.Cu" "*.Mask")
			(remove_unused_layers no)
			(net "GND")
			(clearance 0.0508)
			(thermal_gap 0.0508)
		)
		(pad "B1" thru_hole circle
			(at 0 1.199896 180)
			(size 0.906272 0.906272)
			(drill 0.499872)
			(layers "*.Cu" "*.Mask")
			(remove_unused_layers no)
			(net "GND")
			(clearance 0.0508)
			(thermal_gap 0.0508)
		)
		(pad "B3" thru_hole circle
			(at 3.999992 1.199896 180)
			(size 0.906272 0.906272)
			(drill 0.499872)
			(layers "*.Cu" "*.Mask")
			(remove_unused_layers no)
			(net "GND")
			(clearance 0.0508)
			(thermal_gap 0.0508)
		)
		(pad "B5" thru_hole circle
			(at 7.999984 1.199896 180)
			(size 0.906272 0.906272)
			(drill 0.499872)
			(layers "*.Cu" "*.Mask")
			(remove_unused_layers no)
			(net "GND")
			(clearance 0.0508)
			(thermal_gap 0.0508)
		)
		(pad "B7" thru_hole circle
			(at 11.999976 1.199896 180)
			(size 0.906272 0.906272)
			(drill 0.499872)
			(layers "*.Cu" "*.Mask")
			(remove_unused_layers no)
			(net "GND")
			(clearance 0.0508)
			(thermal_gap 0.0508)
		)
		(pad "D2" thru_hole circle
			(at 1.999996 3.800094 180)
			(size 0.906272 0.906272)
			(drill 0.499872)
			(layers "*.Cu" "*.Mask")
			(remove_unused_layers no)
			(net "GND")
			(clearance 0.0508)
			(thermal_gap 0.0508)
		)
		(pad "D4" thru_hole circle
			(at 5.999988 3.800094 180)
			(size 0.906272 0.906272)
			(drill 0.499872)
			(layers "*.Cu" "*.Mask")
			(remove_unused_layers no)
			(net "GND")
			(clearance 0.0508)
			(thermal_gap 0.0508)
		)
		(pad "D6" thru_hole circle
			(at 9.99998 3.800094 180)
			(size 0.906272 0.906272)
			(drill 0.499872)
			(layers "*.Cu" "*.Mask")
			(remove_unused_layers no)
			(net "GND")
			(clearance 0.0508)
			(thermal_gap 0.0508)
		)
		(pad "D8" thru_hole circle
			(at 13.999972 3.800094 180)
			(size 0.906272 0.906272)
			(drill 0.499872)
			(layers "*.Cu" "*.Mask")
			(remove_unused_layers no)
			(net "GND")
			(clearance 0.0508)
			(thermal_gap 0.0508)
		)
		(pad "E1" thru_hole circle
			(at 0 4.800092 180)
			(size 0.906272 0.906272)
			(drill 0.499872)
			(layers "*.Cu" "*.Mask")
			(remove_unused_layers no)
			(net "GND")
			(clearance 0.0508)
			(thermal_gap 0.0508)
		)
		(pad "E3" thru_hole circle
			(at 3.999992 4.800092 180)
			(size 0.906272 0.906272)
			(drill 0.499872)
			(layers "*.Cu" "*.Mask")
			(remove_unused_layers no)
			(net "GND")
			(clearance 0.0508)
			(thermal_gap 0.0508)
		)
		(pad "E5" thru_hole circle
			(at 7.999984 4.800092 180)
			(size 0.906272 0.906272)
			(drill 0.499872)
			(layers "*.Cu" "*.Mask")
			(remove_unused_layers no)
			(net "GND")
			(clearance 0.0508)
			(thermal_gap 0.0508)
		)
		(pad "E7" thru_hole circle
			(at 11.999976 4.800092 180)
			(size 0.906272 0.906272)
			(drill 0.499872)
			(layers "*.Cu" "*.Mask")
			(remove_unused_layers no)
			(net "GND")
			(clearance 0.0508)
			(thermal_gap 0.0508)
		)
		(pad "G2" thru_hole circle
			(at 1.999996 7.400036 180)
			(size 0.906272 0.906272)
			(drill 0.499872)
			(layers "*.Cu" "*.Mask")
			(remove_unused_layers no)
			(net "GND")
			(clearance 0.0508)
			(thermal_gap 0.0508)
		)
		(pad "G4" thru_hole circle
			(at 5.999988 7.400036 180)
			(size 0.906272 0.906272)
			(drill 0.499872)
			(layers "*.Cu" "*.Mask")
			(remove_unused_layers no)
			(net "GND")
			(clearance 0.0508)
			(thermal_gap 0.0508)
		)
		(pad "G6" thru_hole circle
			(at 9.99998 7.400036 180)
			(size 0.906272 0.906272)
			(drill 0.499872)
			(layers "*.Cu" "*.Mask")
			(remove_unused_layers no)
			(net "GND")
			(clearance 0.0508)
			(thermal_gap 0.0508)
		)
		(pad "G8" thru_hole circle
			(at 13.999972 7.400036 180)
			(size 0.906272 0.906272)
			(drill 0.499872)
			(layers "*.Cu" "*.Mask")
			(remove_unused_layers no)
			(net "GND")
			(clearance 0.0508)
			(thermal_gap 0.0508)
		)
		(pad "H1" thru_hole circle
			(at 0 8.400034 180)
			(size 0.906272 0.906272)
			(drill 0.499872)
			(layers "*.Cu" "*.Mask")
			(remove_unused_layers no)
			(net "GND")
			(clearance 0.0508)
			(thermal_gap 0.0508)
		)
		(pad "H3" thru_hole circle
			(at 3.999992 8.400034 180)
			(size 0.906272 0.906272)
			(drill 0.499872)
			(layers "*.Cu" "*.Mask")
			(remove_unused_layers no)
			(net "GND")
			(clearance 0.0508)
			(thermal_gap 0.0508)
		)
		(pad "H5" thru_hole circle
			(at 7.999984 8.400034 180)
			(size 0.906272 0.906272)
			(drill 0.499872)
			(layers "*.Cu" "*.Mask")
			(remove_unused_layers no)
			(net "GND")
			(clearance 0.0508)
			(thermal_gap 0.0508)
		)
		(pad "H7" thru_hole circle
			(at 11.999976 8.400034 180)
			(size 0.906272 0.906272)
			(drill 0.499872)
			(layers "*.Cu" "*.Mask")
			(remove_unused_layers no)
			(net "GND")
			(clearance 0.0508)
			(thermal_gap 0.0508)
		)
		(pad "J2" thru_hole circle
			(at 1.999996 10.999978 180)
			(size 0.906272 0.906272)
			(drill 0.499872)
			(layers "*.Cu" "*.Mask")
			(remove_unused_layers no)
			(net "GND")
			(clearance 0.0508)
			(thermal_gap 0.0508)
		)
		(pad "J4" thru_hole circle
			(at 5.999988 10.999978 180)
			(size 0.906272 0.906272)
			(drill 0.499872)
			(layers "*.Cu" "*.Mask")
			(remove_unused_layers no)
			(net "GND")
			(clearance 0.0508)
			(thermal_gap 0.0508)
		)
		(pad "J6" thru_hole circle
			(at 9.99998 10.999978 180)
			(size 0.906272 0.906272)
			(drill 0.499872)
			(layers "*.Cu" "*.Mask")
			(remove_unused_layers no)
			(net "GND")
			(clearance 0.0508)
			(thermal_gap 0.0508)
		)
	)
)
